(kicad_pcb
	(version 20260206)
	(generator "pcbnew")
	(generator_version "10.0")
	(general
		(thickness 1.6)
		(legacy_teardrops no)
	)
	(paper "A4")
	(title_block
		(title "panther-plus-userver — 13130-1b_20150205.brd")
		(comment 1 "Honey Badger (Wiwynn) / footprints 238-245 of 1509")
	)
	(layers
		(0 "F.Cu" signal "TOP")
		(4 "In1.Cu" signal "L2")
		(6 "In2.Cu" signal "L3")
		(8 "In3.Cu" signal "L4")
		(10 "In4.Cu" signal "L5")
		(12 "In5.Cu" signal "L6")
		(14 "In6.Cu" signal "L7")
		(16 "In7.Cu" signal "L8")
		(18 "In8.Cu" signal "L9")
		(20 "In9.Cu" signal "L10")
		(22 "In10.Cu" signal "L11")
		(2 "B.Cu" signal "BOTTOM")
		(9 "F.Adhes" user "F.Adhesive")
		(11 "B.Adhes" user "B.Adhesive")
		(13 "F.Paste" user "Package Geometry/Pastemask Top")
		(15 "B.Paste" user "Package Geometry/Pastemask Bottom")
		(5 "F.SilkS" user "Ref Des/Silkscreen Top")
		(7 "B.SilkS" user "Ref Des/Silkscreen Bottom")
		(1 "F.Mask" user "Board Geometry/Soldermask Top")
		(3 "B.Mask" user "Board Geometry/Soldermask Bottom")
		(17 "Dwgs.User" user "User.Drawings")
		(19 "Cmts.User" user "User.Comments")
		(21 "Eco1.User" user "User.Eco1")
		(23 "Eco2.User" user "User.Eco2")
		(25 "Edge.Cuts" user "Board Geometry/Outline")
		(27 "Margin" user)
		(31 "F.CrtYd" user "Package Geometry/Place Bound Top")
		(29 "B.CrtYd" user "Package Geometry/Place Bound Bottom")
		(35 "F.Fab" user "Ref Des/Assembly Top")
		(33 "B.Fab" user "Ref Des/Assembly Bottom")
	)
	(footprint ""
		(layer "F.Cu")
		(at 36.068 -39.116)
		(property "Reference" "R244"
			(at 0 0 0)
			(layer "F.SilkS")
			(hide yes)
			(effects
				(font
					(size 1.27 1.27)
				)
			)
		)
		(property "Value" "1KR2F-3-GP"
			(at 0.064008 -3.993896 0)
			(unlocked yes)
			(layer "F.Fab")
			(hide yes)
			(effects
				(font
					(size 1.016 1.016)
					(thickness 0.1524)
				)
			)
		)
		(property "Device Type" "R402H16"
			(at 0.064008 -5.517896 0)
			(unlocked yes)
			(layer "F.Fab")
			(hide yes)
			(effects
				(font
					(size 1.016 1.016)
					(thickness 0.1524)
				)
			)
		)
		(duplicate_pad_numbers_are_jumpers no)
		(fp_rect
			(start -0.381 0.8382)
			(end 0.381 -0.8382)
			(stroke
				(width 0)
				(type default)
			)
			(fill no)
			(layer "F.CrtYd")
		)
		(fp_rect
			(start -0.381 0.8382)
			(end 0.381 -0.8382)
			(stroke
				(width 0)
				(type default)
			)
			(fill no)
			(layer "F.Fab")
		)
		(pad "1" smd custom
			(at 0 -0.4318)
			(size 0.127 0.127)
			(layers "F.Cu" "F.Mask" "F.Paste")
			(net "CORE_PWROK")
			(options
				(clearance outline)
				(anchor circle)
			)
			(primitives
				(gr_poly
					(pts
						(arc
							(start -0.2032 -0.2794)
							(mid -0.239121 -0.264521)
							(end -0.254 -0.2286)
						)
						(arc
							(start -0.254 0.2286)
							(mid -0.239121 0.264521)
							(end -0.2032 0.2794)
						)
						(arc
							(start 0.2032 0.2794)
							(mid 0.239121 0.264521)
							(end 0.254 0.2286)
						)
						(arc
							(start 0.254 -0.2286)
							(mid 0.239121 -0.264521)
							(end 0.2032 -0.2794)
						)
					)
					(width 0)
					(fill yes)
				)
			)
		)
		(pad "2" smd custom
			(at 0 0.4318)
			(size 0.127 0.127)
			(layers "F.Cu" "F.Mask" "F.Paste")
			(net "XDP_PWRGD_IN")
			(options
				(clearance outline)
				(anchor circle)
			)
			(primitives
				(gr_poly
					(pts
						(arc
							(start -0.2032 -0.2794)
							(mid -0.239121 -0.264521)
							(end -0.254 -0.2286)
						)
						(arc
							(start -0.254 0.2286)
							(mid -0.239121 0.264521)
							(end -0.2032 0.2794)
						)
						(arc
							(start 0.2032 0.2794)
							(mid 0.239121 0.264521)
							(end 0.254 0.2286)
						)
						(arc
							(start 0.254 -0.2286)
							(mid 0.239121 -0.264521)
							(end 0.2032 -0.2794)
						)
					)
					(width 0)
					(fill yes)
				)
			)
		)
	)
	(footprint ""
		(layer "F.Cu")
		(at 184.15 -48.26 -90)
		(property "Reference" "U26"
			(at 0 0 270)
			(layer "F.SilkS")
			(hide yes)
			(effects
				(font
					(size 1.27 1.27)
				)
			)
		)
		(property "Value" "ISL90727WIE627Z-TK-2-GP"
			(at -2.3622 -8.2042 270)
			(unlocked yes)
			(layer "F.Fab")
			(hide yes)
			(effects
				(font
					(size 1.016 1.016)
					(thickness 0.1524)
				)
			)
		)
		(property "Device Type" "SC70-6H44"
			(at -2.3622 -10.1092 270)
			(unlocked yes)
			(layer "F.Fab")
			(hide yes)
			(effects
				(font
					(size 1.016 1.016)
					(thickness 0.1524)
				)
			)
		)
		(duplicate_pad_numbers_are_jumpers no)
		(fp_line
			(start -1.0033 0.4699)
			(end 1.0033 0.4699)
			(stroke
				(width 0.1524)
				(type default)
			)
			(layer "F.SilkS")
		)
		(fp_line
			(start 1.0033 0.4699)
			(end 1.0033 -0.4699)
			(stroke
				(width 0.1524)
				(type default)
			)
			(layer "F.SilkS")
		)
		(fp_line
			(start -1.1811 0.1905)
			(end -1.1811 1.1938)
			(stroke
				(width 0.381)
				(type default)
			)
			(layer "F.SilkS")
		)
		(fp_line
			(start -1.0033 -0.4699)
			(end -1.0033 0.4699)
			(stroke
				(width 0.1524)
				(type default)
			)
			(layer "F.SilkS")
		)
		(fp_line
			(start 1.0033 -0.4699)
			(end -1.0033 -0.4699)
			(stroke
				(width 0.1524)
				(type default)
			)
			(layer "F.SilkS")
		)
		(fp_poly
			(pts
				(xy 1.2573 -0.8763) (xy 1.2573 0.8763) (xy 0.9779 0.8763) (xy 0.9779 1.4097) (xy -0.9779 1.4097)
				(xy -0.9779 0.8763) (xy -1.2573 0.8763) (xy -1.2573 -0.8763) (xy -0.9779 -0.8763) (xy -0.9779 -1.4097)
				(xy 0.9779 -1.4097) (xy 0.9779 -0.8763)
			)
			(stroke
				(width 0)
				(type default)
			)
			(fill no)
			(layer "F.CrtYd")
		)
		(fp_poly
			(pts
				(xy 1.2573 -0.8763) (xy 1.2573 0.8763) (xy 0.9779 0.8763) (xy 0.9779 1.4097) (xy -0.9779 1.4097)
				(xy -0.9779 0.8763) (xy -1.2573 0.8763) (xy -1.2573 -0.8763) (xy -0.9779 -0.8763) (xy -0.9779 -1.4097)
				(xy 0.9779 -1.4097) (xy 0.9779 -0.8763)
			)
			(stroke
				(width 0)
				(type default)
			)
			(fill no)
			(layer "F.Fab")
		)
		(pad "1" smd rect
			(at -0.65024 0.94996 270)
			(size 0.4064 0.6604)
			(layers "F.Cu" "F.Mask" "F.Paste")
			(net "P3V3_STBY")
		)
		(pad "2" smd rect
			(at 0 0.94996 270)
			(size 0.4064 0.6604)
			(layers "F.Cu" "F.Mask" "F.Paste")
			(net "GND")
		)
		(pad "3" smd rect
			(at 0.65024 0.94996 270)
			(size 0.4064 0.6604)
			(layers "F.Cu" "F.Mask" "F.Paste")
			(net "SMB_DPOT_CLK")
		)
		(pad "4" smd rect
			(at 0.65024 -0.94996 270)
			(size 0.4064 0.6604)
			(layers "F.Cu" "F.Mask" "F.Paste")
			(net "SMB_DPOT_DATA")
		)
		(pad "5" smd rect
			(at 0 -0.94996 270)
			(size 0.4064 0.6604)
			(layers "F.Cu" "F.Mask" "F.Paste")
			(net "PV_VDDR_VREF_RW")
		)
		(pad "6" smd rect
			(at -0.65024 -0.94996 270)
			(size 0.4064 0.6604)
			(layers "F.Cu" "F.Mask" "F.Paste")
			(net "PV_VDDR")
		)
	)
	(footprint ""
		(layer "F.Cu")
		(at 64.262 -32.258 -90)
		(property "Reference" "R240"
			(at 0 0 270)
			(layer "F.SilkS")
			(hide yes)
			(effects
				(font
					(size 1.27 1.27)
				)
			)
		)
		(property "Value" "1KR2F-3-GP"
			(at 0.064008 -3.993896 270)
			(unlocked yes)
			(layer "F.Fab")
			(hide yes)
			(effects
				(font
					(size 1.016 1.016)
					(thickness 0.1524)
				)
			)
		)
		(property "Device Type" "R402H16"
			(at 0.064008 -5.517896 270)
			(unlocked yes)
			(layer "F.Fab")
			(hide yes)
			(effects
				(font
					(size 1.016 1.016)
					(thickness 0.1524)
				)
			)
		)
		(duplicate_pad_numbers_are_jumpers no)
		(fp_rect
			(start -0.381 0.8382)
			(end 0.381 -0.8382)
			(stroke
				(width 0)
				(type default)
			)
			(fill no)
			(layer "F.CrtYd")
		)
		(fp_rect
			(start -0.381 0.8382)
			(end 0.381 -0.8382)
			(stroke
				(width 0)
				(type default)
			)
			(fill no)
			(layer "F.Fab")
		)
		(pad "1" smd custom
			(at 0 -0.4318 270)
			(size 0.127 0.127)
			(layers "F.Cu" "F.Mask" "F.Paste")
			(net "P1V8")
			(options
				(clearance outline)
				(anchor circle)
			)
			(primitives
				(gr_poly
					(pts
						(arc
							(start -0.2032 -0.2794)
							(mid -0.239121 -0.264521)
							(end -0.254 -0.2286)
						)
						(arc
							(start -0.254 0.2286)
							(mid -0.239121 0.264521)
							(end -0.2032 0.2794)
						)
						(arc
							(start 0.2032 0.2794)
							(mid 0.239121 0.264521)
							(end 0.254 0.2286)
						)
						(arc
							(start 0.254 -0.2286)
							(mid 0.239121 -0.264521)
							(end 0.2032 -0.2794)
						)
					)
					(width 0)
					(fill yes)
				)
			)
		)
		(pad "2" smd custom
			(at 0 0.4318 270)
			(size 0.127 0.127)
			(layers "F.Cu" "F.Mask" "F.Paste")
			(net "P1V8_B")
			(options
				(clearance outline)
				(anchor circle)
			)
			(primitives
				(gr_poly
					(pts
						(arc
							(start -0.2032 -0.2794)
							(mid -0.239121 -0.264521)
							(end -0.254 -0.2286)
						)
						(arc
							(start -0.254 0.2286)
							(mid -0.239121 0.264521)
							(end -0.2032 0.2794)
						)
						(arc
							(start 0.2032 0.2794)
							(mid 0.239121 0.264521)
							(end 0.254 0.2286)
						)
						(arc
							(start 0.254 -0.2286)
							(mid 0.239121 -0.264521)
							(end 0.2032 -0.2794)
						)
					)
					(width 0)
					(fill yes)
				)
			)
		)
	)
	(footprint ""
		(layer "F.Cu")
		(at 182.499 -52.9336)
		(property "Reference" "C92"
			(at 0 0 0)
			(layer "F.SilkS")
			(hide yes)
			(effects
				(font
					(size 1.27 1.27)
				)
			)
		)
		(property "Value" "SC1U6D3V2KX-GP"
			(at 1.1811 -2.7051 0)
			(unlocked yes)
			(layer "F.Fab")
			(hide yes)
			(effects
				(font
					(size 1.016 1.016)
					(thickness 0.1524)
				)
			)
		)
		(property "Device Type" "C402H22"
			(at 1.1811 -4.2291 0)
			(unlocked yes)
			(layer "F.Fab")
			(hide yes)
			(effects
				(font
					(size 1.016 1.016)
					(thickness 0.1524)
				)
			)
		)
		(duplicate_pad_numbers_are_jumpers no)
		(fp_rect
			(start -0.381 0.7366)
			(end 0.381 -0.7366)
			(stroke
				(width 0)
				(type default)
			)
			(fill no)
			(layer "F.CrtYd")
		)
		(fp_rect
			(start -0.381 0.7366)
			(end 0.381 -0.7366)
			(stroke
				(width 0)
				(type default)
			)
			(fill no)
			(layer "F.Fab")
		)
		(pad "1" smd custom
			(at 0 -0.4572)
			(size 0.1143 0.1143)
			(layers "F.Cu" "F.Mask" "F.Paste")
			(net "PV_VDDR_VREF_A")
			(options
				(clearance outline)
				(anchor circle)
			)
			(primitives
				(gr_poly
					(pts
						(arc
							(start -0.254 -0.1778)
							(mid -0.239121 -0.213721)
							(end -0.2032 -0.2286)
						)
						(arc
							(start 0.2032 -0.2286)
							(mid 0.239121 -0.213721)
							(end 0.254 -0.1778)
						)
						(arc
							(start 0.254 0.1778)
							(mid 0.239121 0.213721)
							(end 0.2032 0.2286)
						)
						(arc
							(start -0.2032 0.2286)
							(mid -0.239121 0.213721)
							(end -0.254 0.1778)
						)
					)
					(width 0)
					(fill yes)
				)
			)
		)
		(pad "2" smd custom
			(at 0 0.4572)
			(size 0.1143 0.1143)
			(layers "F.Cu" "F.Mask" "F.Paste")
			(net "GND")
			(options
				(clearance outline)
				(anchor circle)
			)
			(primitives
				(gr_poly
					(pts
						(arc
							(start -0.254 -0.1778)
							(mid -0.239121 -0.213721)
							(end -0.2032 -0.2286)
						)
						(arc
							(start 0.2032 -0.2286)
							(mid 0.239121 -0.213721)
							(end 0.254 -0.1778)
						)
						(arc
							(start 0.254 0.1778)
							(mid 0.239121 0.213721)
							(end 0.2032 0.2286)
						)
						(arc
							(start -0.2032 0.2286)
							(mid -0.239121 0.213721)
							(end -0.254 0.1778)
						)
					)
					(width 0)
					(fill yes)
				)
			)
		)
	)
	(footprint ""
		(layer "F.Cu")
		(at 29.083 -42.037 -90)
		(property "Reference" "PR194"
			(at 0 0 270)
			(layer "F.SilkS")
			(hide yes)
			(effects
				(font
					(size 1.27 1.27)
				)
			)
		)
		(property "Value" "0R6J-3-GP"
			(at 0.0127 -3.2766 270)
			(unlocked yes)
			(layer "F.Fab")
			(hide yes)
			(effects
				(font
					(size 1.016 1.016)
					(thickness 0.1524)
				)
			)
		)
		(property "Device Type" "R1206H28"
			(at 0.0127 -4.8006 270)
			(unlocked yes)
			(layer "F.Fab")
			(hide yes)
			(effects
				(font
					(size 1.016 1.016)
					(thickness 0.1524)
				)
			)
		)
		(duplicate_pad_numbers_are_jumpers no)
		(fp_line
			(start -0.7239 0.381)
			(end 0.7239 0.381)
			(stroke
				(width 0.1524)
				(type default)
			)
			(layer "F.SilkS")
		)
		(fp_line
			(start 0.7239 0.381)
			(end 0.7239 -0.381)
			(stroke
				(width 0.1524)
				(type default)
			)
			(layer "F.SilkS")
		)
		(fp_line
			(start -0.7239 -0.381)
			(end -0.7239 0.381)
			(stroke
				(width 0.1524)
				(type default)
			)
			(layer "F.SilkS")
		)
		(fp_line
			(start 0.7239 -0.381)
			(end -0.7239 -0.381)
			(stroke
				(width 0.1524)
				(type default)
			)
			(layer "F.SilkS")
		)
		(fp_poly
			(pts
				(xy -0.7239 0.381) (xy 0.7239 0.381) (xy 0.7239 -0.381) (xy -0.7239 -0.381)
			)
			(stroke
				(width 0)
				(type default)
			)
			(fill yes)
			(layer "F.SilkS")
		)
		(fp_rect
			(start -1.0541 1.9812)
			(end 1.0541 -1.9812)
			(stroke
				(width 0)
				(type default)
			)
			(fill no)
			(layer "F.CrtYd")
		)
		(fp_rect
			(start -1.0541 1.9812)
			(end 1.0541 -1.9812)
			(stroke
				(width 0)
				(type default)
			)
			(fill no)
			(layer "F.Fab")
		)
		(pad "1" smd rect
			(at 0 -1.3462 270)
			(size 1.8542 1.016)
			(layers "F.Cu" "F.Mask" "F.Paste")
			(net "P3V3_STBY")
		)
		(pad "2" smd rect
			(at 0 1.3462 270)
			(size 1.8542 1.016)
			(layers "F.Cu" "F.Mask" "F.Paste")
			(net "P3V3_STBY_OUT")
		)
	)
	(footprint ""
		(layer "F.Cu")
		(at 69.596 -31.496 90)
		(property "Reference" "R124"
			(at 0 0 90)
			(layer "F.SilkS")
			(hide yes)
			(effects
				(font
					(size 1.27 1.27)
				)
			)
		)
		(property "Value" "4K7R2F-GP"
			(at 0.064008 -3.993896 90)
			(unlocked yes)
			(layer "F.Fab")
			(hide yes)
			(effects
				(font
					(size 1.016 1.016)
					(thickness 0.1524)
				)
			)
		)
		(property "Device Type" "R402H16"
			(at 0.064008 -5.517896 90)
			(unlocked yes)
			(layer "F.Fab")
			(hide yes)
			(effects
				(font
					(size 1.016 1.016)
					(thickness 0.1524)
				)
			)
		)
		(duplicate_pad_numbers_are_jumpers no)
		(fp_rect
			(start -0.381 0.8382)
			(end 0.381 -0.8382)
			(stroke
				(width 0)
				(type default)
			)
			(fill no)
			(layer "F.CrtYd")
		)
		(fp_rect
			(start -0.381 0.8382)
			(end 0.381 -0.8382)
			(stroke
				(width 0)
				(type default)
			)
			(fill no)
			(layer "F.Fab")
		)
		(pad "1" smd custom
			(at 0 -0.4318 90)
			(size 0.127 0.127)
			(layers "F.Cu" "F.Mask" "F.Paste")
			(net "P3V3_CPU")
			(options
				(clearance outline)
				(anchor circle)
			)
			(primitives
				(gr_poly
					(pts
						(arc
							(start -0.2032 -0.2794)
							(mid -0.239121 -0.264521)
							(end -0.254 -0.2286)
						)
						(arc
							(start -0.254 0.2286)
							(mid -0.239121 0.264521)
							(end -0.2032 0.2794)
						)
						(arc
							(start 0.2032 0.2794)
							(mid 0.239121 0.264521)
							(end 0.254 0.2286)
						)
						(arc
							(start 0.254 -0.2286)
							(mid 0.239121 -0.264521)
							(end 0.2032 -0.2794)
						)
					)
					(width 0)
					(fill yes)
				)
			)
		)
		(pad "2" smd custom
			(at 0 0.4318 90)
			(size 0.127 0.127)
			(layers "F.Cu" "F.Mask" "F.Paste")
			(net "BD_ID_2")
			(options
				(clearance outline)
				(anchor circle)
			)
			(primitives
				(gr_poly
					(pts
						(arc
							(start -0.2032 -0.2794)
							(mid -0.239121 -0.264521)
							(end -0.254 -0.2286)
						)
						(arc
							(start -0.254 0.2286)
							(mid -0.239121 0.264521)
							(end -0.2032 0.2794)
						)
						(arc
							(start 0.2032 0.2794)
							(mid 0.239121 0.264521)
							(end 0.254 0.2286)
						)
						(arc
							(start 0.254 -0.2286)
							(mid 0.239121 -0.264521)
							(end 0.2032 -0.2794)
						)
					)
					(width 0)
					(fill yes)
				)
			)
		)
	)
	(footprint ""
		(layer "F.Cu")
		(at 79.883 -61.595)
		(property "Reference" "C69"
			(at 0 0 0)
			(layer "F.SilkS")
			(hide yes)
			(effects
				(font
					(size 1.27 1.27)
				)
			)
		)
		(property "Value" "SCD1U16V2KX-3GP"
			(at 1.1811 -2.7051 0)
			(unlocked yes)
			(layer "F.Fab")
			(hide yes)
			(effects
				(font
					(size 1.016 1.016)
					(thickness 0.1524)
				)
			)
		)
		(property "Device Type" "C402H22"
			(at 1.1811 -4.2291 0)
			(unlocked yes)
			(layer "F.Fab")
			(hide yes)
			(effects
				(font
					(size 1.016 1.016)
					(thickness 0.1524)
				)
			)
		)
		(duplicate_pad_numbers_are_jumpers no)
		(fp_rect
			(start -0.381 0.7366)
			(end 0.381 -0.7366)
			(stroke
				(width 0)
				(type default)
			)
			(fill no)
			(layer "F.CrtYd")
		)
		(fp_rect
			(start -0.381 0.7366)
			(end 0.381 -0.7366)
			(stroke
				(width 0)
				(type default)
			)
			(fill no)
			(layer "F.Fab")
		)
		(pad "1" smd custom
			(at 0 -0.4572)
			(size 0.1143 0.1143)
			(layers "F.Cu" "F.Mask" "F.Paste")
			(net "PV_VDDR_SENSE")
			(options
				(clearance outline)
				(anchor circle)
			)
			(primitives
				(gr_poly
					(pts
						(arc
							(start -0.254 -0.1778)
							(mid -0.239121 -0.213721)
							(end -0.2032 -0.2286)
						)
						(arc
							(start 0.2032 -0.2286)
							(mid 0.239121 -0.213721)
							(end 0.254 -0.1778)
						)
						(arc
							(start 0.254 0.1778)
							(mid 0.239121 0.213721)
							(end 0.2032 0.2286)
						)
						(arc
							(start -0.2032 0.2286)
							(mid -0.239121 0.213721)
							(end -0.254 0.1778)
						)
					)
					(width 0)
					(fill yes)
				)
			)
		)
		(pad "2" smd custom
			(at 0 0.4572)
			(size 0.1143 0.1143)
			(layers "F.Cu" "F.Mask" "F.Paste")
			(net "GND")
			(options
				(clearance outline)
				(anchor circle)
			)
			(primitives
				(gr_poly
					(pts
						(arc
							(start -0.254 -0.1778)
							(mid -0.239121 -0.213721)
							(end -0.2032 -0.2286)
						)
						(arc
							(start 0.2032 -0.2286)
							(mid 0.239121 -0.213721)
							(end 0.254 -0.1778)
						)
						(arc
							(start 0.254 0.1778)
							(mid 0.239121 0.213721)
							(end 0.2032 0.2286)
						)
						(arc
							(start -0.2032 0.2286)
							(mid -0.239121 0.213721)
							(end -0.254 0.1778)
						)
					)
					(width 0)
					(fill yes)
				)
			)
		)
	)
	(footprint ""
		(layer "F.Cu")
		(at 128.143 -34.29 90)
		(property "Reference" "R27"
			(at 0 0 90)
			(layer "F.SilkS")
			(hide yes)
			(effects
				(font
					(size 1.27 1.27)
				)
			)
		)
		(property "Value" "4K7R2F-GP"
			(at 0.064008 -3.993896 90)
			(unlocked yes)
			(layer "F.Fab")
			(hide yes)
			(effects
				(font
					(size 1.016 1.016)
					(thickness 0.1524)
				)
			)
		)
		(property "Device Type" "R402H16"
			(at 0.064008 -5.517896 90)
			(unlocked yes)
			(layer "F.Fab")
			(hide yes)
			(effects
				(font
					(size 1.016 1.016)
					(thickness 0.1524)
				)
			)
		)
		(duplicate_pad_numbers_are_jumpers no)
		(fp_rect
			(start -0.381 0.8382)
			(end 0.381 -0.8382)
			(stroke
				(width 0)
				(type default)
			)
			(fill no)
			(layer "F.CrtYd")
		)
		(fp_rect
			(start -0.381 0.8382)
			(end 0.381 -0.8382)
			(stroke
				(width 0)
				(type default)
			)
			(fill no)
			(layer "F.Fab")
		)
		(pad "1" smd custom
			(at 0 -0.4318 90)
			(size 0.127 0.127)
			(layers "F.Cu" "F.Mask" "F.Paste")
			(net "P3V3_STBY")
			(options
				(clearance outline)
				(anchor circle)
			)
			(primitives
				(gr_poly
					(pts
						(arc
							(start -0.2032 -0.2794)
							(mid -0.239121 -0.264521)
							(end -0.254 -0.2286)
						)
						(arc
							(start -0.254 0.2286)
							(mid -0.239121 0.264521)
							(end -0.2032 0.2794)
						)
						(arc
							(start 0.2032 0.2794)
							(mid 0.239121 0.264521)
							(end 0.254 0.2286)
						)
						(arc
							(start 0.254 -0.2286)
							(mid 0.239121 -0.264521)
							(end 0.2032 -0.2794)
						)
					)
					(width 0)
					(fill yes)
				)
			)
		)
		(pad "2" smd custom
			(at 0 0.4318 90)
			(size 0.127 0.127)
			(layers "F.Cu" "F.Mask" "F.Paste")
			(net "SMB_PECI_LV_DATA")
			(options
				(clearance outline)
				(anchor circle)
			)
			(primitives
				(gr_poly
					(pts
						(arc
							(start -0.2032 -0.2794)
							(mid -0.239121 -0.264521)
							(end -0.254 -0.2286)
						)
						(arc
							(start -0.254 0.2286)
							(mid -0.239121 0.264521)
							(end -0.2032 0.2794)
						)
						(arc
							(start 0.2032 0.2794)
							(mid 0.239121 0.264521)
							(end 0.254 0.2286)
						)
						(arc
							(start 0.254 -0.2286)
							(mid 0.239121 -0.264521)
							(end 0.2032 -0.2794)
						)
					)
					(width 0)
					(fill yes)
				)
			)
		)
	)
)
